(kicad_pcb
	(version 20260206)
	(generator "pcbnew")
	(generator_version "10.0")
	(general
		(thickness 1.6)
		(legacy_teardrops no)
	)
	(paper "A4")
	(title_block
		(title "9054_F0T_PDB_BD_GPU_F_V04_1213_1550_OCP.brd")
		(comment 1 "Grand Teton / footprints 546-551 of 608")
	)
	(layers
		(0 "F.Cu" signal "TOP")
		(4 "In1.Cu" signal "GND")
		(6 "In2.Cu" signal "IN1")
		(8 "In3.Cu" signal "GND1")
		(10 "In4.Cu" signal "VCC")
		(12 "In5.Cu" signal "VCC1")
		(14 "In6.Cu" signal "GND2")
		(16 "In7.Cu" signal "IN2")
		(18 "In8.Cu" signal "GND3")
		(2 "B.Cu" signal "BOTTOM")
		(9 "F.Adhes" user "F.Adhesive")
		(11 "B.Adhes" user "B.Adhesive")
		(13 "F.Paste" user "Package Geometry/Pastemask Top")
		(15 "B.Paste" user "Package Geometry/Pastemask Bottom")
		(5 "F.SilkS" user "Ref Des/Silkscreen Top")
		(7 "B.SilkS" user "Ref Des/Silkscreen Bottom")
		(1 "F.Mask" user "Board Geometry/Soldermask Top")
		(3 "B.Mask" user "Board Geometry/Soldermask Bottom")
		(17 "Dwgs.User" user "User.Drawings")
		(19 "Cmts.User" user "User.Comments")
		(21 "Eco1.User" user "User.Eco1")
		(23 "Eco2.User" user "User.Eco2")
		(25 "Edge.Cuts" user "Board Geometry/Outline")
		(27 "Margin" user)
		(31 "F.CrtYd" user "Package Geometry/Place Bound Top")
		(29 "B.CrtYd" user "Package Geometry/Place Bound Bottom")
		(35 "F.Fab" user "Ref Des/Assembly Top")
		(33 "B.Fab" user "Ref Des/Assembly Bottom")
	)
	(footprint ""
		(layer "B.Cu")
		(at 341.4014 -51.9176)
		(property "Reference" "PC8"
			(at 0 0 0)
			(layer "B.SilkS")
			(hide yes)
			(effects
				(font
					(size 1.27 1.27)
				)
				(justify mirror)
			)
		)
		(property "Value" ""
			(at 0 0 0)
			(layer "B.Fab")
			(effects
				(font
					(size 1.27 1.27)
				)
				(justify mirror)
			)
		)
		(duplicate_pad_numbers_are_jumpers no)
		(fp_line
			(start -1.2954 -0.5842)
			(end -1.2954 0.5842)
			(stroke
				(width 0.1524)
				(type default)
			)
			(layer "B.SilkS")
		)
		(fp_line
			(start -1.2954 0.5842)
			(end 1.2954 0.5842)
			(stroke
				(width 0.1524)
				(type default)
			)
			(layer "B.SilkS")
		)
		(fp_line
			(start 1.2954 -0.5842)
			(end -1.2954 -0.5842)
			(stroke
				(width 0.1524)
				(type default)
			)
			(layer "B.SilkS")
		)
		(fp_line
			(start 1.2954 0.5842)
			(end 1.2954 -0.5842)
			(stroke
				(width 0.1524)
				(type default)
			)
			(layer "B.SilkS")
		)
		(fp_line
			(start -1.1938 -0.4064)
			(end -1.1938 0.4064)
			(stroke
				(width 0.1)
				(type default)
			)
			(layer "B.Fab")
		)
		(fp_line
			(start -1.1938 0.4064)
			(end -0.8636 0.4064)
			(stroke
				(width 0.1)
				(type default)
			)
			(layer "B.Fab")
		)
		(fp_line
			(start -0.8636 -0.4572)
			(end -0.8636 -0.4064)
			(stroke
				(width 0.1)
				(type default)
			)
			(layer "B.Fab")
		)
		(fp_line
			(start -0.8636 -0.4064)
			(end -1.1938 -0.4064)
			(stroke
				(width 0.1)
				(type default)
			)
			(layer "B.Fab")
		)
		(fp_line
			(start -0.8636 0.4064)
			(end -0.8636 0.4572)
			(stroke
				(width 0.1)
				(type default)
			)
			(layer "B.Fab")
		)
		(fp_line
			(start -0.8636 0.4572)
			(end 0.8636 0.4572)
			(stroke
				(width 0.1)
				(type default)
			)
			(layer "B.Fab")
		)
		(fp_line
			(start 0.8636 -0.4572)
			(end -0.8636 -0.4572)
			(stroke
				(width 0.1)
				(type default)
			)
			(layer "B.Fab")
		)
		(fp_line
			(start 0.8636 -0.4064)
			(end 0.8636 -0.4572)
			(stroke
				(width 0.1)
				(type default)
			)
			(layer "B.Fab")
		)
		(fp_line
			(start 0.8636 0.4064)
			(end 1.1938 0.4064)
			(stroke
				(width 0.1)
				(type default)
			)
			(layer "B.Fab")
		)
		(fp_line
			(start 0.8636 0.4572)
			(end 0.8636 0.4064)
			(stroke
				(width 0.1)
				(type default)
			)
			(layer "B.Fab")
		)
		(fp_line
			(start 1.1938 -0.4064)
			(end 0.8636 -0.4064)
			(stroke
				(width 0.1)
				(type default)
			)
			(layer "B.Fab")
		)
		(fp_line
			(start 1.1938 0.4064)
			(end 1.1938 -0.4064)
			(stroke
				(width 0.1)
				(type default)
			)
			(layer "B.Fab")
		)
		(pad "1" smd rect
			(at 0.7366 0 270)
			(size 0.7112 0.8128)
			(layers "B.Cu" "B.Mask" "B.Paste")
			(net "GND")
		)
		(pad "2" smd rect
			(at -0.7366 0 270)
			(size 0.7112 0.8128)
			(layers "B.Cu" "B.Mask" "B.Paste")
			(net "P52V_HS1_GATE_R1")
		)
	)
	(footprint ""
		(layer "B.Cu")
		(at 413.639 -37.084 180)
		(property "Reference" "R5934"
			(at 0 0 0)
			(layer "B.SilkS")
			(hide yes)
			(effects
				(font
					(size 1.27 1.27)
				)
				(justify mirror)
			)
		)
		(property "Value" ""
			(at 0 0 0)
			(layer "B.Fab")
			(effects
				(font
					(size 1.27 1.27)
				)
				(justify mirror)
			)
		)
		(duplicate_pad_numbers_are_jumpers no)
		(fp_line
			(start 0.7874 0.4064)
			(end 0.7874 -0.4064)
			(stroke
				(width 0.1524)
				(type default)
			)
			(layer "B.SilkS")
		)
		(fp_line
			(start 0.7874 -0.4064)
			(end -0.7874 -0.4064)
			(stroke
				(width 0.1524)
				(type default)
			)
			(layer "B.SilkS")
		)
		(fp_line
			(start -0.7874 0.4064)
			(end 0.7874 0.4064)
			(stroke
				(width 0.1524)
				(type default)
			)
			(layer "B.SilkS")
		)
		(fp_line
			(start -0.7874 -0.4064)
			(end -0.7874 0.4064)
			(stroke
				(width 0.1524)
				(type default)
			)
			(layer "B.SilkS")
		)
		(fp_line
			(start 0.67945 0.3048)
			(end 0.67945 -0.305054)
			(stroke
				(width 0.1)
				(type default)
			)
			(layer "B.Fab")
		)
		(fp_line
			(start 0.67945 -0.305054)
			(end 0.12065 -0.305054)
			(stroke
				(width 0.1)
				(type default)
			)
			(layer "B.Fab")
		)
		(fp_line
			(start 0.12065 0.3048)
			(end 0.67945 0.3048)
			(stroke
				(width 0.1)
				(type default)
			)
			(layer "B.Fab")
		)
		(fp_line
			(start 0.12065 0.2794)
			(end 0.12065 0.3048)
			(stroke
				(width 0.1)
				(type default)
			)
			(layer "B.Fab")
		)
		(fp_line
			(start 0.12065 -0.2794)
			(end -0.12065 -0.2794)
			(stroke
				(width 0.1)
				(type default)
			)
			(layer "B.Fab")
		)
		(fp_line
			(start 0.12065 -0.305054)
			(end 0.12065 -0.2794)
			(stroke
				(width 0.1)
				(type default)
			)
			(layer "B.Fab")
		)
		(fp_line
			(start -0.120396 0.3048)
			(end -0.120396 0.2794)
			(stroke
				(width 0.1)
				(type default)
			)
			(layer "B.Fab")
		)
		(fp_line
			(start -0.120396 0.2794)
			(end 0.12065 0.2794)
			(stroke
				(width 0.1)
				(type default)
			)
			(layer "B.Fab")
		)
		(fp_line
			(start -0.12065 -0.2794)
			(end -0.12065 -0.3048)
			(stroke
				(width 0.1)
				(type default)
			)
			(layer "B.Fab")
		)
		(fp_line
			(start -0.12065 -0.3048)
			(end -0.67945 -0.3048)
			(stroke
				(width 0.1)
				(type default)
			)
			(layer "B.Fab")
		)
		(fp_line
			(start -0.67945 0.3048)
			(end -0.120396 0.3048)
			(stroke
				(width 0.1)
				(type default)
			)
			(layer "B.Fab")
		)
		(fp_line
			(start -0.67945 -0.3048)
			(end -0.67945 0.3048)
			(stroke
				(width 0.1)
				(type default)
			)
			(layer "B.Fab")
		)
		(pad "1" smd circle
			(at 0.40005 0)
			(size 0 0)
			(layers "B.Cu" "B.Mask" "B.Paste")
			(net "P3V3_AUX")
		)
		(pad "2" smd circle
			(at -0.40005 0)
			(size 0 0)
			(layers "B.Cu" "B.Mask" "B.Paste")
			(net "PCA9555_2_A2")
		)
	)
	(footprint ""
		(layer "B.Cu")
		(at 343.535 -49.276 180)
		(property "Reference" "PC584"
			(at 0 0 0)
			(layer "B.SilkS")
			(hide yes)
			(effects
				(font
					(size 1.27 1.27)
				)
				(justify mirror)
			)
		)
		(property "Value" ""
			(at 0 0 0)
			(layer "B.Fab")
			(effects
				(font
					(size 1.27 1.27)
				)
				(justify mirror)
			)
		)
		(duplicate_pad_numbers_are_jumpers no)
		(fp_line
			(start 1.2954 0.5842)
			(end 1.2954 -0.5842)
			(stroke
				(width 0.1524)
				(type default)
			)
			(layer "B.SilkS")
		)
		(fp_line
			(start 1.2954 -0.5842)
			(end -1.2954 -0.5842)
			(stroke
				(width 0.1524)
				(type default)
			)
			(layer "B.SilkS")
		)
		(fp_line
			(start -1.2954 0.5842)
			(end 1.2954 0.5842)
			(stroke
				(width 0.1524)
				(type default)
			)
			(layer "B.SilkS")
		)
		(fp_line
			(start -1.2954 -0.5842)
			(end -1.2954 0.5842)
			(stroke
				(width 0.1524)
				(type default)
			)
			(layer "B.SilkS")
		)
		(fp_line
			(start 1.1938 0.4064)
			(end 1.1938 -0.4064)
			(stroke
				(width 0.1)
				(type default)
			)
			(layer "B.Fab")
		)
		(fp_line
			(start 1.1938 -0.4064)
			(end 0.8636 -0.4064)
			(stroke
				(width 0.1)
				(type default)
			)
			(layer "B.Fab")
		)
		(fp_line
			(start 0.8636 0.4572)
			(end 0.8636 0.4064)
			(stroke
				(width 0.1)
				(type default)
			)
			(layer "B.Fab")
		)
		(fp_line
			(start 0.8636 0.4064)
			(end 1.1938 0.4064)
			(stroke
				(width 0.1)
				(type default)
			)
			(layer "B.Fab")
		)
		(fp_line
			(start 0.8636 -0.4064)
			(end 0.8636 -0.4572)
			(stroke
				(width 0.1)
				(type default)
			)
			(layer "B.Fab")
		)
		(fp_line
			(start 0.8636 -0.4572)
			(end -0.8636 -0.4572)
			(stroke
				(width 0.1)
				(type default)
			)
			(layer "B.Fab")
		)
		(fp_line
			(start -0.8636 0.4572)
			(end 0.8636 0.4572)
			(stroke
				(width 0.1)
				(type default)
			)
			(layer "B.Fab")
		)
		(fp_line
			(start -0.8636 0.4064)
			(end -0.8636 0.4572)
			(stroke
				(width 0.1)
				(type default)
			)
			(layer "B.Fab")
		)
		(fp_line
			(start -0.8636 -0.4064)
			(end -1.1938 -0.4064)
			(stroke
				(width 0.1)
				(type default)
			)
			(layer "B.Fab")
		)
		(fp_line
			(start -0.8636 -0.4572)
			(end -0.8636 -0.4064)
			(stroke
				(width 0.1)
				(type default)
			)
			(layer "B.Fab")
		)
		(fp_line
			(start -1.1938 0.4064)
			(end -0.8636 0.4064)
			(stroke
				(width 0.1)
				(type default)
			)
			(layer "B.Fab")
		)
		(fp_line
			(start -1.1938 -0.4064)
			(end -1.1938 0.4064)
			(stroke
				(width 0.1)
				(type default)
			)
			(layer "B.Fab")
		)
		(pad "1" smd rect
			(at 0.7366 0 90)
			(size 0.7112 0.8128)
			(layers "B.Cu" "B.Mask" "B.Paste")
			(net "P52V_HS1_GATE_RC")
		)
		(pad "2" smd rect
			(at -0.7366 0 90)
			(size 0.7112 0.8128)
			(layers "B.Cu" "B.Mask" "B.Paste")
			(net "P52V_HS1")
		)
	)
	(footprint ""
		(layer "B.Cu")
		(at 111.2774 -44.3484 -90)
		(property "Reference" "R5867"
			(at 0 0 90)
			(layer "B.SilkS")
			(hide yes)
			(effects
				(font
					(size 1.27 1.27)
				)
				(justify mirror)
			)
		)
		(property "Value" ""
			(at 0 0 90)
			(layer "B.Fab")
			(effects
				(font
					(size 1.27 1.27)
				)
				(justify mirror)
			)
		)
		(duplicate_pad_numbers_are_jumpers no)
		(fp_line
			(start -0.7874 0.4064)
			(end 0.7874 0.4064)
			(stroke
				(width 0.1524)
				(type default)
			)
			(layer "B.SilkS")
		)
		(fp_line
			(start 0.7874 0.4064)
			(end 0.7874 -0.4064)
			(stroke
				(width 0.1524)
				(type default)
			)
			(layer "B.SilkS")
		)
		(fp_line
			(start -0.7874 -0.4064)
			(end -0.7874 0.4064)
			(stroke
				(width 0.1524)
				(type default)
			)
			(layer "B.SilkS")
		)
		(fp_line
			(start 0.7874 -0.4064)
			(end -0.7874 -0.4064)
			(stroke
				(width 0.1524)
				(type default)
			)
			(layer "B.SilkS")
		)
		(fp_line
			(start -0.67945 0.3048)
			(end -0.120396 0.3048)
			(stroke
				(width 0.1)
				(type default)
			)
			(layer "B.Fab")
		)
		(fp_line
			(start -0.120396 0.3048)
			(end -0.120396 0.2794)
			(stroke
				(width 0.1)
				(type default)
			)
			(layer "B.Fab")
		)
		(fp_line
			(start 0.12065 0.3048)
			(end 0.67945 0.3048)
			(stroke
				(width 0.1)
				(type default)
			)
			(layer "B.Fab")
		)
		(fp_line
			(start 0.67945 0.3048)
			(end 0.67945 -0.305054)
			(stroke
				(width 0.1)
				(type default)
			)
			(layer "B.Fab")
		)
		(fp_line
			(start -0.120396 0.2794)
			(end 0.12065 0.2794)
			(stroke
				(width 0.1)
				(type default)
			)
			(layer "B.Fab")
		)
		(fp_line
			(start 0.12065 0.2794)
			(end 0.12065 0.3048)
			(stroke
				(width 0.1)
				(type default)
			)
			(layer "B.Fab")
		)
		(fp_line
			(start -0.12065 -0.2794)
			(end -0.12065 -0.3048)
			(stroke
				(width 0.1)
				(type default)
			)
			(layer "B.Fab")
		)
		(fp_line
			(start 0.12065 -0.2794)
			(end -0.12065 -0.2794)
			(stroke
				(width 0.1)
				(type default)
			)
			(layer "B.Fab")
		)
		(fp_line
			(start -0.67945 -0.3048)
			(end -0.67945 0.3048)
			(stroke
				(width 0.1)
				(type default)
			)
			(layer "B.Fab")
		)
		(fp_line
			(start -0.12065 -0.3048)
			(end -0.67945 -0.3048)
			(stroke
				(width 0.1)
				(type default)
			)
			(layer "B.Fab")
		)
		(fp_line
			(start 0.12065 -0.305054)
			(end 0.12065 -0.2794)
			(stroke
				(width 0.1)
				(type default)
			)
			(layer "B.Fab")
		)
		(fp_line
			(start 0.67945 -0.305054)
			(end 0.12065 -0.305054)
			(stroke
				(width 0.1)
				(type default)
			)
			(layer "B.Fab")
		)
		(pad "1" smd circle
			(at 0.40005 0 90)
			(size 0 0)
			(layers "B.Cu" "B.Mask" "B.Paste")
			(net "P52V_HS2_1272_GATE")
		)
		(pad "2" smd circle
			(at -0.40005 0 90)
			(size 0 0)
			(layers "B.Cu" "B.Mask" "B.Paste")
			(net "P52V_HS2_GATE2_R")
		)
	)
	(footprint ""
		(layer "B.Cu")
		(at 285.369 -92.075 180)
		(property "Reference" "U34"
			(at -5.1435 -1.56337 0)
			(unlocked yes)
			(layer "B.SilkS")
			(effects
				(font
					(size 0.7874 0.5842)
					(thickness 0.1524)
				)
				(justify left mirror)
			)
		)
		(property "Value" ""
			(at 0 0 0)
			(layer "B.Fab")
			(effects
				(font
					(size 1.27 1.27)
				)
				(justify mirror)
			)
		)
		(duplicate_pad_numbers_are_jumpers no)
		(fp_line
			(start 1.733296 1.549908)
			(end -1.733296 1.549908)
			(stroke
				(width 0.1524)
				(type default)
			)
			(layer "B.SilkS")
		)
		(fp_line
			(start 1.733296 -1.549908)
			(end 1.733296 1.549908)
			(stroke
				(width 0.1524)
				(type default)
			)
			(layer "B.SilkS")
		)
		(fp_line
			(start 0.660908 -1.549908)
			(end 1.733296 -1.549908)
			(stroke
				(width 0.1524)
				(type default)
			)
			(layer "B.SilkS")
		)
		(fp_line
			(start 0 -0.889)
			(end 0.660908 -1.549908)
			(stroke
				(width 0.1524)
				(type default)
			)
			(layer "B.SilkS")
		)
		(fp_line
			(start -0.660908 -1.549908)
			(end 0 -0.889)
			(stroke
				(width 0.1524)
				(type default)
			)
			(layer "B.SilkS")
		)
		(fp_line
			(start -1.733296 1.549908)
			(end -1.733296 -1.549908)
			(stroke
				(width 0.1524)
				(type default)
			)
			(layer "B.SilkS")
		)
		(fp_line
			(start -1.733296 -1.549908)
			(end -0.660908 -1.549908)
			(stroke
				(width 0.1524)
				(type default)
			)
			(layer "B.SilkS")
		)
		(fp_poly
			(pts
				(xy 1.016 -2.286) (xy 1.524 -2.286) (xy 1.27 -1.778)
			)
			(stroke
				(width 0)
				(type default)
			)
			(fill yes)
			(layer "B.SilkS")
		)
		(fp_line
			(start 0.849884 1.549908)
			(end -0.849884 1.549908)
			(stroke
				(width 0.1)
				(type default)
			)
			(layer "B.Fab")
		)
		(fp_line
			(start 0.849884 -1.549908)
			(end 0.849884 1.549908)
			(stroke
				(width 0.1)
				(type default)
			)
			(layer "B.Fab")
		)
		(fp_line
			(start -0.849884 1.549908)
			(end -0.849884 -1.549908)
			(stroke
				(width 0.1)
				(type default)
			)
			(layer "B.Fab")
		)
		(fp_line
			(start -0.849884 -1.549908)
			(end 0.849884 -1.549908)
			(stroke
				(width 0.1)
				(type default)
			)
			(layer "B.Fab")
		)
		(fp_poly
			(pts
				(xy 2.4384 -1.20396) (xy 2.4384 -0.69596) (xy 1.9304 -0.94996)
			)
			(stroke
				(width 0)
				(type default)
			)
			(fill yes)
			(layer "B.Fab")
		)
		(pad "1" smd rect
			(at 1.199896 -0.94996 90)
			(size 0.5588 0.8128)
			(layers "B.Cu" "B.Mask" "B.Paste")
			(net "FM_HS1_EN_BUSBAR")
		)
		(pad "2" smd rect
			(at 1.199896 0 90)
			(size 0.5588 0.8128)
			(layers "B.Cu" "B.Mask" "B.Paste")
			(net "FM_HS1_EN_FUSE")
		)
		(pad "3" smd rect
			(at 1.199896 0.94996 90)
			(size 0.5588 0.8128)
			(layers "B.Cu" "B.Mask" "B.Paste")
			(net "GND")
		)
		(pad "4" smd rect
			(at -1.199896 0.94996 90)
			(size 0.5588 0.8128)
			(layers "B.Cu" "B.Mask" "B.Paste")
			(net "P52V_HS1_EN")
		)
		(pad "5" smd rect
			(at -1.199896 -0.94996 90)
			(size 0.5588 0.8128)
			(layers "B.Cu" "B.Mask" "B.Paste")
			(net "P3V3_AND")
		)
	)
	(footprint ""
		(layer "B.Cu")
		(at 285.9024 -73.025 180)
		(property "Reference" "R5855"
			(at 0 0 0)
			(layer "B.SilkS")
			(hide yes)
			(effects
				(font
					(size 1.27 1.27)
				)
				(justify mirror)
			)
		)
		(property "Value" ""
			(at 0 0 0)
			(layer "B.Fab")
			(effects
				(font
					(size 1.27 1.27)
				)
				(justify mirror)
			)
		)
		(duplicate_pad_numbers_are_jumpers no)
		(fp_line
			(start 0.7874 0.4064)
			(end 0.7874 -0.4064)
			(stroke
				(width 0.1524)
				(type default)
			)
			(layer "B.SilkS")
		)
		(fp_line
			(start 0.7874 -0.4064)
			(end -0.7874 -0.4064)
			(stroke
				(width 0.1524)
				(type default)
			)
			(layer "B.SilkS")
		)
		(fp_line
			(start -0.7874 0.4064)
			(end 0.7874 0.4064)
			(stroke
				(width 0.1524)
				(type default)
			)
			(layer "B.SilkS")
		)
		(fp_line
			(start -0.7874 -0.4064)
			(end -0.7874 0.4064)
			(stroke
				(width 0.1524)
				(type default)
			)
			(layer "B.SilkS")
		)
		(fp_line
			(start 0.67945 0.3048)
			(end 0.67945 -0.305054)
			(stroke
				(width 0.1)
				(type default)
			)
			(layer "B.Fab")
		)
		(fp_line
			(start 0.67945 -0.305054)
			(end 0.12065 -0.305054)
			(stroke
				(width 0.1)
				(type default)
			)
			(layer "B.Fab")
		)
		(fp_line
			(start 0.12065 0.3048)
			(end 0.67945 0.3048)
			(stroke
				(width 0.1)
				(type default)
			)
			(layer "B.Fab")
		)
		(fp_line
			(start 0.12065 0.2794)
			(end 0.12065 0.3048)
			(stroke
				(width 0.1)
				(type default)
			)
			(layer "B.Fab")
		)
		(fp_line
			(start 0.12065 -0.2794)
			(end -0.12065 -0.2794)
			(stroke
				(width 0.1)
				(type default)
			)
			(layer "B.Fab")
		)
		(fp_line
			(start 0.12065 -0.305054)
			(end 0.12065 -0.2794)
			(stroke
				(width 0.1)
				(type default)
			)
			(layer "B.Fab")
		)
		(fp_line
			(start -0.120396 0.3048)
			(end -0.120396 0.2794)
			(stroke
				(width 0.1)
				(type default)
			)
			(layer "B.Fab")
		)
		(fp_line
			(start -0.120396 0.2794)
			(end 0.12065 0.2794)
			(stroke
				(width 0.1)
				(type default)
			)
			(layer "B.Fab")
		)
		(fp_line
			(start -0.12065 -0.2794)
			(end -0.12065 -0.3048)
			(stroke
				(width 0.1)
				(type default)
			)
			(layer "B.Fab")
		)
		(fp_line
			(start -0.12065 -0.3048)
			(end -0.67945 -0.3048)
			(stroke
				(width 0.1)
				(type default)
			)
			(layer "B.Fab")
		)
		(fp_line
			(start -0.67945 0.3048)
			(end -0.120396 0.3048)
			(stroke
				(width 0.1)
				(type default)
			)
			(layer "B.Fab")
		)
		(fp_line
			(start -0.67945 -0.3048)
			(end -0.67945 0.3048)
			(stroke
				(width 0.1)
				(type default)
			)
			(layer "B.Fab")
		)
		(pad "1" smd circle
			(at 0.40005 0)
			(size 0 0)
			(layers "B.Cu" "B.Mask" "B.Paste")
			(net "SMB_P52V_PDB_SDA")
		)
		(pad "2" smd circle
			(at -0.40005 0)
			(size 0 0)
			(layers "B.Cu" "B.Mask" "B.Paste")
			(net "SMB_P52V_HS1_SDAI")
		)
	)
)
